# T6G (Grand Teton) — schematic netlist excerpt (pin names and nets, part order shuffled) for the footprints in the layout excerpt that follows; sources: Cadence DE-HDL packaged netlist, KiCad conversion of 04192023_DAF0TMB3IC0_F0TG_MB_C_brd_V02_OCP.brd

PR408  Q_RES  0 5% CHIP  pkg 0402LF  page 224 : A = NC_PVDD11_S3_P1_IMON7 ; B = GND
PR400  Q_RES  10 1% CHIP  pkg 0402LF  page 226 : A = PVDD18_S5_P1_FB_RC ; B = VSENSE_PVDD18_S5_P1_DP

(kicad_pcb
	(version 20260206)
	(generator "pcbnew")
	(generator_version "10.0")
	(general
		(thickness 1.6)
		(legacy_teardrops no)
	)
	(paper "A4")
	(title_block
		(title "04192023_DAF0TMB3IC0_F0TG_MB_C_brd_V02_OCP.brd")
		(comment 1 "Grand Teton / footprints 1358-1359 of 8354")
	)
	(layers
		(0 "F.Cu" signal "TOP")
		(4 "In1.Cu" signal "GND")
		(6 "In2.Cu" signal "IN1")
		(8 "In3.Cu" signal "GND1")
		(10 "In4.Cu" signal "IN2")
		(12 "In5.Cu" signal "GND2")
		(14 "In6.Cu" signal "IN3")
		(16 "In7.Cu" signal "GND3")
		(18 "In8.Cu" signal "VCC")
		(20 "In9.Cu" signal "VCC1")
		(22 "In10.Cu" signal "GND4")
		(24 "In11.Cu" signal "IN4")
		(26 "In12.Cu" signal "GND5")
		(28 "In13.Cu" signal "IN5")
		(30 "In14.Cu" signal "GND6")
		(32 "In15.Cu" signal "IN6")
		(34 "In16.Cu" signal "GND7")
		(2 "B.Cu" signal "BOTTOM")
		(9 "F.Adhes" user "F.Adhesive")
		(11 "B.Adhes" user "B.Adhesive")
		(13 "F.Paste" user "Package Geometry/Pastemask Top")
		(15 "B.Paste" user "Package Geometry/Pastemask Bottom")
		(5 "F.SilkS" user "Ref Des/Silkscreen Top")
		(7 "B.SilkS" user "Ref Des/Silkscreen Bottom")
		(1 "F.Mask" user "Board Geometry/Soldermask Top")
		(3 "B.Mask" user "Board Geometry/Soldermask Bottom")
		(17 "Dwgs.User" user "User.Drawings")
		(19 "Cmts.User" user "User.Comments")
		(21 "Eco1.User" user "User.Eco1")
		(23 "Eco2.User" user "User.Eco2")
		(25 "Edge.Cuts" user "Board Geometry/Outline")
		(27 "Margin" user)
		(31 "F.CrtYd" user "Package Geometry/Place Bound Top")
		(29 "B.CrtYd" user "Package Geometry/Place Bound Bottom")
		(35 "F.Fab" user "Ref Des/Assembly Top")
		(33 "B.Fab" user "Ref Des/Assembly Bottom")
	)
	(footprint ""
		(layer "F.Cu")
		(at 166.074344 -344.153998 -90)
		(property "Reference" "PR408"
			(at 0 0 270)
			(layer "F.SilkS")
			(hide yes)
			(effects
				(font
					(size 1.27 1.27)
				)
			)
		)
		(property "Value" ""
			(at 0 0 270)
			(layer "F.Fab")
			(effects
				(font
					(size 1.27 1.27)
				)
			)
		)
		(duplicate_pad_numbers_are_jumpers no)
		(fp_line
			(start -0.7874 0.4064)
			(end -0.7874 -0.4064)
			(stroke
				(width 0.1524)
				(type default)
			)
			(layer "F.SilkS")
		)
		(fp_line
			(start 0.7874 0.4064)
			(end -0.7874 0.4064)
			(stroke
				(width 0.1524)
				(type default)
			)
			(layer "F.SilkS")
		)
		(fp_line
			(start -0.7874 -0.4064)
			(end 0.7874 -0.4064)
			(stroke
				(width 0.1524)
				(type default)
			)
			(layer "F.SilkS")
		)
		(fp_line
			(start 0.7874 -0.4064)
			(end 0.7874 0.4064)
			(stroke
				(width 0.1524)
				(type default)
			)
			(layer "F.SilkS")
		)
		(fp_line
			(start -0.67945 0.3048)
			(end -0.67945 -0.305054)
			(stroke
				(width 0.1)
				(type default)
			)
			(layer "F.Fab")
		)
		(fp_line
			(start -0.12065 0.3048)
			(end -0.67945 0.3048)
			(stroke
				(width 0.1)
				(type default)
			)
			(layer "F.Fab")
		)
		(fp_line
			(start 0.120396 0.3048)
			(end 0.120396 0.2794)
			(stroke
				(width 0.1)
				(type default)
			)
			(layer "F.Fab")
		)
		(fp_line
			(start 0.67945 0.3048)
			(end 0.120396 0.3048)
			(stroke
				(width 0.1)
				(type default)
			)
			(layer "F.Fab")
		)
		(fp_line
			(start -0.12065 0.2794)
			(end -0.12065 0.3048)
			(stroke
				(width 0.1)
				(type default)
			)
			(layer "F.Fab")
		)
		(fp_line
			(start 0.120396 0.2794)
			(end -0.12065 0.2794)
			(stroke
				(width 0.1)
				(type default)
			)
			(layer "F.Fab")
		)
		(fp_line
			(start -0.12065 -0.2794)
			(end 0.12065 -0.2794)
			(stroke
				(width 0.1)
				(type default)
			)
			(layer "F.Fab")
		)
		(fp_line
			(start 0.12065 -0.2794)
			(end 0.12065 -0.3048)
			(stroke
				(width 0.1)
				(type default)
			)
			(layer "F.Fab")
		)
		(fp_line
			(start 0.12065 -0.3048)
			(end 0.67945 -0.3048)
			(stroke
				(width 0.1)
				(type default)
			)
			(layer "F.Fab")
		)
		(fp_line
			(start 0.67945 -0.3048)
			(end 0.67945 0.3048)
			(stroke
				(width 0.1)
				(type default)
			)
			(layer "F.Fab")
		)
		(fp_line
			(start -0.67945 -0.305054)
			(end -0.12065 -0.305054)
			(stroke
				(width 0.1)
				(type default)
			)
			(layer "F.Fab")
		)
		(fp_line
			(start -0.12065 -0.305054)
			(end -0.12065 -0.2794)
			(stroke
				(width 0.1)
				(type default)
			)
			(layer "F.Fab")
		)
		(pad "1" smd circle
			(at -0.40005 0 270)
			(size 0 0)
			(layers "F.Cu" "F.Mask" "F.Paste")
			(net "NC_PVDD11_S3_P1_IMON7")
		)
		(pad "2" smd circle
			(at 0.40005 0 270)
			(size 0 0)
			(layers "F.Cu" "F.Mask" "F.Paste")
			(net "GND")
		)
	)
	(footprint ""
		(layer "F.Cu")
		(at 72.463914 -144.881092)
		(property "Reference" "PR400"
			(at 0 0 0)
			(layer "F.SilkS")
			(hide yes)
			(effects
				(font
					(size 1.27 1.27)
				)
			)
		)
		(property "Value" ""
			(at 0 0 0)
			(layer "F.Fab")
			(effects
				(font
					(size 1.27 1.27)
				)
			)
		)
		(duplicate_pad_numbers_are_jumpers no)
		(fp_line
			(start -0.7874 -0.4064)
			(end 0.7874 -0.4064)
			(stroke
				(width 0.1524)
				(type default)
			)
			(layer "F.SilkS")
		)
		(fp_line
			(start -0.7874 0.4064)
			(end -0.7874 -0.4064)
			(stroke
				(width 0.1524)
				(type default)
			)
			(layer "F.SilkS")
		)
		(fp_line
			(start 0.7874 -0.4064)
			(end 0.7874 0.4064)
			(stroke
				(width 0.1524)
				(type default)
			)
			(layer "F.SilkS")
		)
		(fp_line
			(start 0.7874 0.4064)
			(end -0.7874 0.4064)
			(stroke
				(width 0.1524)
				(type default)
			)
			(layer "F.SilkS")
		)
		(fp_line
			(start -0.67945 -0.305054)
			(end -0.12065 -0.305054)
			(stroke
				(width 0.1)
				(type default)
			)
			(layer "F.Fab")
		)
		(fp_line
			(start -0.67945 0.3048)
			(end -0.67945 -0.305054)
			(stroke
				(width 0.1)
				(type default)
			)
			(layer "F.Fab")
		)
		(fp_line
			(start -0.12065 -0.305054)
			(end -0.12065 -0.2794)
			(stroke
				(width 0.1)
				(type default)
			)
			(layer "F.Fab")
		)
		(fp_line
			(start -0.12065 -0.2794)
			(end 0.12065 -0.2794)
			(stroke
				(width 0.1)
				(type default)
			)
			(layer "F.Fab")
		)
		(fp_line
			(start -0.12065 0.2794)
			(end -0.12065 0.3048)
			(stroke
				(width 0.1)
				(type default)
			)
			(layer "F.Fab")
		)
		(fp_line
			(start -0.12065 0.3048)
			(end -0.67945 0.3048)
			(stroke
				(width 0.1)
				(type default)
			)
			(layer "F.Fab")
		)
		(fp_line
			(start 0.120396 0.2794)
			(end -0.12065 0.2794)
			(stroke
				(width 0.1)
				(type default)
			)
			(layer "F.Fab")
		)
		(fp_line
			(start 0.120396 0.3048)
			(end 0.120396 0.2794)
			(stroke
				(width 0.1)
				(type default)
			)
			(layer "F.Fab")
		)
		(fp_line
			(start 0.12065 -0.3048)
			(end 0.67945 -0.3048)
			(stroke
				(width 0.1)
				(type default)
			)
			(layer "F.Fab")
		)
		(fp_line
			(start 0.12065 -0.2794)
			(end 0.12065 -0.3048)
			(stroke
				(width 0.1)
				(type default)
			)
			(layer "F.Fab")
		)
		(fp_line
			(start 0.67945 -0.3048)
			(end 0.67945 0.3048)
			(stroke
				(width 0.1)
				(type default)
			)
			(layer "F.Fab")
		)
		(fp_line
			(start 0.67945 0.3048)
			(end 0.120396 0.3048)
			(stroke
				(width 0.1)
				(type default)
			)
			(layer "F.Fab")
		)
		(pad "1" smd circle
			(at -0.40005 0)
			(size 0 0)
			(layers "F.Cu" "F.Mask" "F.Paste")
			(net "PVDD18_S5_P1_FB_RC")
		)
		(pad "2" smd circle
			(at 0.40005 0)
			(size 0 0)
			(layers "F.Cu" "F.Mask" "F.Paste")
			(net "VSENSE_PVDD18_S5_P1_DP")
		)
	)
)
